# SCM (Grand Teton) — schematic netlist excerpt (pin names and nets, part order shuffled) for the footprints in the layout excerpt that follows; sources: Cadence DE-HDL packaged netlist, KiCad conversion of 12092022_DA0F0TMDCD0_F0T_Management_Board_D_brd_V3_OCP.brd

J23  PICOPROBE_BXA  DELTA-L 4.0 EMPTY  pkg TRIANG_LAUNCH_3PXB  page 58
  \1_p\  = 85_10INCH_IN4_DP
  \2_n\  = 85_10INCH_IN4_DN
  \3_g\  = GND_P1

(kicad_pcb
	(version 20260206)
	(generator "pcbnew")
	(generator_version "10.0")
	(general
		(thickness 1.6)
		(legacy_teardrops no)
	)
	(paper "A4")
	(title_block
		(title "12092022_DA0F0TMDCD0_F0T_Management_Board_D_brd_V3_OCP.brd")
		(comment 1 "Grand Teton / footprints 650-650 of 1440")
	)
	(layers
		(0 "F.Cu" signal "TOP")
		(4 "In1.Cu" signal "GND")
		(6 "In2.Cu" signal "IN1")
		(8 "In3.Cu" signal "GND1")
		(10 "In4.Cu" signal "IN2")
		(12 "In5.Cu" signal "VCC")
		(14 "In6.Cu" signal "VCC1")
		(16 "In7.Cu" signal "IN3")
		(18 "In8.Cu" signal "GND2")
		(20 "In9.Cu" signal "IN4")
		(22 "In10.Cu" signal "GND3")
		(2 "B.Cu" signal "BOTTOM")
		(9 "F.Adhes" user "F.Adhesive")
		(11 "B.Adhes" user "B.Adhesive")
		(13 "F.Paste" user "Package Geometry/Pastemask Top")
		(15 "B.Paste" user "Package Geometry/Pastemask Bottom")
		(5 "F.SilkS" user "Ref Des/Silkscreen Top")
		(7 "B.SilkS" user "Ref Des/Silkscreen Bottom")
		(1 "F.Mask" user "Board Geometry/Soldermask Top")
		(3 "B.Mask" user "Board Geometry/Soldermask Bottom")
		(17 "Dwgs.User" user "User.Drawings")
		(19 "Cmts.User" user "User.Comments")
		(21 "Eco1.User" user "User.Eco1")
		(23 "Eco2.User" user "User.Eco2")
		(25 "Edge.Cuts" user "Board Geometry/Outline")
		(27 "Margin" user)
		(31 "F.CrtYd" user "Package Geometry/Place Bound Top")
		(29 "B.CrtYd" user "Package Geometry/Place Bound Bottom")
		(35 "F.Fab" user "Ref Des/Assembly Top")
		(33 "B.Fab" user "Ref Des/Assembly Bottom")
	)
	(footprint ""
		(layer "F.Cu")
		(at 95.911416 -15.895574 90)
		(property "Reference" "J23"
			(at -1.163574 2.794254 90)
			(unlocked yes)
			(layer "F.SilkS")
			(effects
				(font
					(size 0.7874 0.5842)
					(thickness 0.1524)
				)
				(justify left)
			)
		)
		(property "Value" ""
			(at 0 0 90)
			(layer "F.Fab")
			(effects
				(font
					(size 1.27 1.27)
				)
			)
		)
		(duplicate_pad_numbers_are_jumpers no)
		(fp_line
			(start 1.2192 -2.1082)
			(end 1.2192 -0.804672)
			(stroke
				(width 0.1524)
				(type default)
			)
			(layer "F.SilkS")
		)
		(fp_line
			(start -1.2192 -2.1082)
			(end 1.2192 -2.1082)
			(stroke
				(width 0.1524)
				(type default)
			)
			(layer "F.SilkS")
		)
		(fp_line
			(start 1.2192 0.821944)
			(end 1.2192 2.1082)
			(stroke
				(width 0.1524)
				(type default)
			)
			(layer "F.SilkS")
		)
		(fp_line
			(start 1.2192 2.1082)
			(end -1.2192 2.1082)
			(stroke
				(width 0.1524)
				(type default)
			)
			(layer "F.SilkS")
		)
		(fp_line
			(start -1.2192 2.1082)
			(end -1.2192 -2.1082)
			(stroke
				(width 0.1524)
				(type default)
			)
			(layer "F.SilkS")
		)
		(pad "" np_thru_hole circle
			(at -2.8829 -1.27)
			(size 1.0414 1.0414)
			(drill 1.0414)
			(layers "*.Cu" "*.Mask")
			(clearance 0.381)
			(thermal_gap 0.381)
		)
		(pad "" np_thru_hole circle
			(at -2.8829 1.27)
			(size 1.0414 1.0414)
			(drill 1.0414)
			(layers "*.Cu" "*.Mask")
			(clearance 0.381)
			(thermal_gap 0.381)
		)
		(pad "" np_thru_hole circle
			(at 3.4671 -1.27)
			(size 1.0414 1.0414)
			(drill 1.0414)
			(layers "*.Cu" "*.Mask")
			(clearance 0.381)
			(thermal_gap 0.381)
		)
		(pad "" np_thru_hole circle
			(at 3.4671 1.27)
			(size 1.0414 1.0414)
			(drill 1.0414)
			(layers "*.Cu" "*.Mask")
			(clearance 0.381)
			(thermal_gap 0.381)
		)
		(pad "1" smd rect
			(at 0.8255 -0.249936)
			(size 0.3048 0.508)
			(layers "F.Cu" "F.Mask" "F.Paste")
			(net "85_10INCH_IN4_DP")
		)
		(pad "2" smd rect
			(at 0.8255 0.249936)
			(size 0.3048 0.508)
			(layers "F.Cu" "F.Mask" "F.Paste")
			(net "85_10INCH_IN4_DN")
		)
		(pad "3" smd circle
			(at 0 0 90)
			(size 0 0)
			(layers "F.Cu" "F.Mask" "F.Paste")
			(net "GND_P1")
		)
		(zone
			(layer "F.Cu")
			(hatch none 0.5)
			(connect_pads
				(clearance 0)
			)
			(min_thickness 0.25)
			(keepout
				(tracks not_allowed)
				(vias allowed)
				(pads allowed)
				(copperpour not_allowed)
				(footprints allowed)
			)
			(placement
				(enabled no)
				(sheetname "")
			)
			(fill
				(thermal_gap 0.5)
				(thermal_bridge_width 0.5)
				(island_removal_mode 0)
			)
			(polygon
				(pts
					(xy 95.362776 -17.013174) (xy 95.45828 -17.013174) (xy 95.45828 -16.416274) (xy 95.86468 -16.416274)
					(xy 95.86468 -17.013174) (xy 95.958152 -17.013174) (xy 95.958152 -16.416274) (xy 96.364552 -16.416274)
					(xy 96.364552 -17.013174) (xy 96.460056 -17.013174) (xy 96.460056 -16.314674) (xy 95.362776 -16.314674)
				)
			)
		)
		(zone
			(layers "F.Cu" "B.Cu" "In1.Cu" "In2.Cu" "In3.Cu" "In4.Cu" "In5.Cu" "In6.Cu"
				"In7.Cu" "In8.Cu" "In9.Cu" "In10.Cu"
			)
			(hatch none 0.5)
			(connect_pads
				(clearance 0)
			)
			(min_thickness 0.25)
			(keepout
				(tracks not_allowed)
				(vias allowed)
				(pads allowed)
				(copperpour not_allowed)
				(footprints allowed)
			)
			(placement
				(enabled no)
				(sheetname "")
			)
			(fill
				(thermal_gap 0.5)
				(thermal_bridge_width 0.5)
				(island_removal_mode 0)
			)
			(polygon
				(pts
					(arc
						(start 95.568516 -19.362674)
						(mid 93.714316 -19.362674)
						(end 95.568516 -19.362674)
					)
				)
			)
		)
		(zone
			(layers "F.Cu" "B.Cu" "In1.Cu" "In2.Cu" "In3.Cu" "In4.Cu" "In5.Cu" "In6.Cu"
				"In7.Cu" "In8.Cu" "In9.Cu" "In10.Cu"
			)
			(hatch none 0.5)
			(connect_pads
				(clearance 0)
			)
			(min_thickness 0.25)
			(keepout
				(tracks not_allowed)
				(vias allowed)
				(pads allowed)
				(copperpour not_allowed)
				(footprints allowed)
			)
			(placement
				(enabled no)
				(sheetname "")
			)
			(fill
				(thermal_gap 0.5)
				(thermal_bridge_width 0.5)
				(island_removal_mode 0)
			)
			(polygon
				(pts
					(arc
						(start 95.568516 -13.012674)
						(mid 93.714316 -13.012674)
						(end 95.568516 -13.012674)
					)
				)
			)
		)
		(zone
			(layers "F.Cu" "B.Cu" "In1.Cu" "In2.Cu" "In3.Cu" "In4.Cu" "In5.Cu" "In6.Cu"
				"In7.Cu" "In8.Cu" "In9.Cu" "In10.Cu"
			)
			(hatch none 0.5)
			(connect_pads
				(clearance 0)
			)
			(min_thickness 0.25)
			(keepout
				(tracks not_allowed)
				(vias allowed)
				(pads allowed)
				(copperpour not_allowed)
				(footprints allowed)
			)
			(placement
				(enabled no)
				(sheetname "")
			)
			(fill
				(thermal_gap 0.5)
				(thermal_bridge_width 0.5)
				(island_removal_mode 0)
			)
			(polygon
				(pts
					(arc
						(start 98.108516 -19.362674)
						(mid 96.254316 -19.362674)
						(end 98.108516 -19.362674)
					)
				)
			)
		)
		(zone
			(layers "F.Cu" "B.Cu" "In1.Cu" "In2.Cu" "In3.Cu" "In4.Cu" "In5.Cu" "In6.Cu"
				"In7.Cu" "In8.Cu" "In9.Cu" "In10.Cu"
			)
			(hatch none 0.5)
			(connect_pads
				(clearance 0)
			)
			(min_thickness 0.25)
			(keepout
				(tracks not_allowed)
				(vias allowed)
				(pads allowed)
				(copperpour not_allowed)
				(footprints allowed)
			)
			(placement
				(enabled no)
				(sheetname "")
			)
			(fill
				(thermal_gap 0.5)
				(thermal_bridge_width 0.5)
				(island_removal_mode 0)
			)
			(polygon
				(pts
					(arc
						(start 98.108516 -13.012674)
						(mid 96.254316 -13.012674)
						(end 98.108516 -13.012674)
					)
				)
			)
		)
	)
)
